# SCM (Grand Teton) — schematic netlist excerpt (pin names and nets, part order shuffled) for the footprints in the layout excerpt that follows; sources: Cadence DE-HDL packaged netlist, KiCad conversion of 12092022_DA0F0TMDCD0_F0T_Management_Board_D_brd_V3_OCP.brd

R834  Q_RES  10K 1% EMPTY  pkg 0402LF  page 32 : A = P3V3_RGM ; B = JTAG_SCM_TCK
C304  Q_CAP  0.1UF 25V 10% X7R  pkg 0402  page 25 : A = P3V3_AUX ; B = GND

(kicad_pcb
	(version 20260206)
	(generator "pcbnew")
	(generator_version "10.0")
	(general
		(thickness 1.6)
		(legacy_teardrops no)
	)
	(paper "A4")
	(title_block
		(title "12092022_DA0F0TMDCD0_F0T_Management_Board_D_brd_V3_OCP.brd")
		(comment 1 "Grand Teton / footprints 293-294 of 1440")
	)
	(layers
		(0 "F.Cu" signal "TOP")
		(4 "In1.Cu" signal "GND")
		(6 "In2.Cu" signal "IN1")
		(8 "In3.Cu" signal "GND1")
		(10 "In4.Cu" signal "IN2")
		(12 "In5.Cu" signal "VCC")
		(14 "In6.Cu" signal "VCC1")
		(16 "In7.Cu" signal "IN3")
		(18 "In8.Cu" signal "GND2")
		(20 "In9.Cu" signal "IN4")
		(22 "In10.Cu" signal "GND3")
		(2 "B.Cu" signal "BOTTOM")
		(9 "F.Adhes" user "F.Adhesive")
		(11 "B.Adhes" user "B.Adhesive")
		(13 "F.Paste" user "Package Geometry/Pastemask Top")
		(15 "B.Paste" user "Package Geometry/Pastemask Bottom")
		(5 "F.SilkS" user "Ref Des/Silkscreen Top")
		(7 "B.SilkS" user "Ref Des/Silkscreen Bottom")
		(1 "F.Mask" user "Board Geometry/Soldermask Top")
		(3 "B.Mask" user "Board Geometry/Soldermask Bottom")
		(17 "Dwgs.User" user "User.Drawings")
		(19 "Cmts.User" user "User.Comments")
		(21 "Eco1.User" user "User.Eco1")
		(23 "Eco2.User" user "User.Eco2")
		(25 "Edge.Cuts" user "Board Geometry/Outline")
		(27 "Margin" user)
		(31 "F.CrtYd" user "Package Geometry/Place Bound Top")
		(29 "B.CrtYd" user "Package Geometry/Place Bound Bottom")
		(35 "F.Fab" user "Ref Des/Assembly Top")
		(33 "B.Fab" user "Ref Des/Assembly Bottom")
	)
	(footprint ""
		(layer "F.Cu")
		(at 62.484 -30.861 90)
		(property "Reference" "R834"
			(at 0 0 90)
			(layer "F.SilkS")
			(hide yes)
			(effects
				(font
					(size 1.27 1.27)
				)
			)
		)
		(property "Value" ""
			(at 0 0 90)
			(layer "F.Fab")
			(effects
				(font
					(size 1.27 1.27)
				)
			)
		)
		(duplicate_pad_numbers_are_jumpers no)
		(fp_line
			(start 0.7874 -0.4064)
			(end 0.7874 0.4064)
			(stroke
				(width 0.1524)
				(type default)
			)
			(layer "F.SilkS")
		)
		(fp_line
			(start -0.7874 -0.4064)
			(end 0.7874 -0.4064)
			(stroke
				(width 0.1524)
				(type default)
			)
			(layer "F.SilkS")
		)
		(fp_line
			(start 0.7874 0.4064)
			(end -0.7874 0.4064)
			(stroke
				(width 0.1524)
				(type default)
			)
			(layer "F.SilkS")
		)
		(fp_line
			(start -0.7874 0.4064)
			(end -0.7874 -0.4064)
			(stroke
				(width 0.1524)
				(type default)
			)
			(layer "F.SilkS")
		)
		(fp_line
			(start -0.12065 -0.305054)
			(end -0.12065 -0.2794)
			(stroke
				(width 0.1)
				(type default)
			)
			(layer "F.Fab")
		)
		(fp_line
			(start -0.67945 -0.305054)
			(end -0.12065 -0.305054)
			(stroke
				(width 0.1)
				(type default)
			)
			(layer "F.Fab")
		)
		(fp_line
			(start 0.67945 -0.3048)
			(end 0.67945 0.3048)
			(stroke
				(width 0.1)
				(type default)
			)
			(layer "F.Fab")
		)
		(fp_line
			(start 0.12065 -0.3048)
			(end 0.67945 -0.3048)
			(stroke
				(width 0.1)
				(type default)
			)
			(layer "F.Fab")
		)
		(fp_line
			(start 0.12065 -0.2794)
			(end 0.12065 -0.3048)
			(stroke
				(width 0.1)
				(type default)
			)
			(layer "F.Fab")
		)
		(fp_line
			(start -0.12065 -0.2794)
			(end 0.12065 -0.2794)
			(stroke
				(width 0.1)
				(type default)
			)
			(layer "F.Fab")
		)
		(fp_line
			(start 0.120396 0.2794)
			(end -0.12065 0.2794)
			(stroke
				(width 0.1)
				(type default)
			)
			(layer "F.Fab")
		)
		(fp_line
			(start -0.12065 0.2794)
			(end -0.12065 0.3048)
			(stroke
				(width 0.1)
				(type default)
			)
			(layer "F.Fab")
		)
		(fp_line
			(start 0.67945 0.3048)
			(end 0.120396 0.3048)
			(stroke
				(width 0.1)
				(type default)
			)
			(layer "F.Fab")
		)
		(fp_line
			(start 0.120396 0.3048)
			(end 0.120396 0.2794)
			(stroke
				(width 0.1)
				(type default)
			)
			(layer "F.Fab")
		)
		(fp_line
			(start -0.12065 0.3048)
			(end -0.67945 0.3048)
			(stroke
				(width 0.1)
				(type default)
			)
			(layer "F.Fab")
		)
		(fp_line
			(start -0.67945 0.3048)
			(end -0.67945 -0.305054)
			(stroke
				(width 0.1)
				(type default)
			)
			(layer "F.Fab")
		)
		(pad "1" smd circle
			(at -0.40005 0 90)
			(size 0 0)
			(layers "F.Cu" "F.Mask" "F.Paste")
			(net "P3V3_RGM")
		)
		(pad "2" smd circle
			(at 0.40005 0 90)
			(size 0 0)
			(layers "F.Cu" "F.Mask" "F.Paste")
			(net "JTAG_SCM_TCK")
		)
	)
	(footprint ""
		(layer "F.Cu")
		(at 16.637 -46.3042 90)
		(property "Reference" "C304"
			(at 0 0 90)
			(layer "F.SilkS")
			(hide yes)
			(effects
				(font
					(size 1.27 1.27)
				)
			)
		)
		(property "Value" ""
			(at 0 0 90)
			(layer "F.Fab")
			(effects
				(font
					(size 1.27 1.27)
				)
			)
		)
		(duplicate_pad_numbers_are_jumpers no)
		(fp_line
			(start 0.7874 -0.4064)
			(end 0.7874 0.4064)
			(stroke
				(width 0.1524)
				(type default)
			)
			(layer "F.SilkS")
		)
		(fp_line
			(start -0.7874 -0.4064)
			(end 0.7874 -0.4064)
			(stroke
				(width 0.1524)
				(type default)
			)
			(layer "F.SilkS")
		)
		(fp_line
			(start 0.7874 0.4064)
			(end -0.7874 0.4064)
			(stroke
				(width 0.1524)
				(type default)
			)
			(layer "F.SilkS")
		)
		(fp_line
			(start -0.7874 0.4064)
			(end -0.7874 -0.4064)
			(stroke
				(width 0.1524)
				(type default)
			)
			(layer "F.SilkS")
		)
		(fp_line
			(start -0.12065 -0.305054)
			(end -0.12065 -0.2794)
			(stroke
				(width 0.1)
				(type default)
			)
			(layer "F.Fab")
		)
		(fp_line
			(start -0.67945 -0.305054)
			(end -0.12065 -0.305054)
			(stroke
				(width 0.1)
				(type default)
			)
			(layer "F.Fab")
		)
		(fp_line
			(start 0.67945 -0.3048)
			(end 0.67945 0.3048)
			(stroke
				(width 0.1)
				(type default)
			)
			(layer "F.Fab")
		)
		(fp_line
			(start 0.12065 -0.3048)
			(end 0.67945 -0.3048)
			(stroke
				(width 0.1)
				(type default)
			)
			(layer "F.Fab")
		)
		(fp_line
			(start 0.12065 -0.2794)
			(end 0.12065 -0.3048)
			(stroke
				(width 0.1)
				(type default)
			)
			(layer "F.Fab")
		)
		(fp_line
			(start -0.12065 -0.2794)
			(end 0.12065 -0.2794)
			(stroke
				(width 0.1)
				(type default)
			)
			(layer "F.Fab")
		)
		(fp_line
			(start 0.120396 0.2794)
			(end -0.12065 0.2794)
			(stroke
				(width 0.1)
				(type default)
			)
			(layer "F.Fab")
		)
		(fp_line
			(start -0.12065 0.2794)
			(end -0.12065 0.3048)
			(stroke
				(width 0.1)
				(type default)
			)
			(layer "F.Fab")
		)
		(fp_line
			(start 0.67945 0.3048)
			(end 0.120396 0.3048)
			(stroke
				(width 0.1)
				(type default)
			)
			(layer "F.Fab")
		)
		(fp_line
			(start 0.120396 0.3048)
			(end 0.120396 0.2794)
			(stroke
				(width 0.1)
				(type default)
			)
			(layer "F.Fab")
		)
		(fp_line
			(start -0.12065 0.3048)
			(end -0.67945 0.3048)
			(stroke
				(width 0.1)
				(type default)
			)
			(layer "F.Fab")
		)
		(fp_line
			(start -0.67945 0.3048)
			(end -0.67945 -0.305054)
			(stroke
				(width 0.1)
				(type default)
			)
			(layer "F.Fab")
		)
		(pad "1" smd circle
			(at -0.40005 0 90)
			(size 0 0)
			(layers "F.Cu" "F.Mask" "F.Paste")
			(net "P3V3_AUX")
		)
		(pad "2" smd circle
			(at 0.40005 0 90)
			(size 0 0)
			(layers "F.Cu" "F.Mask" "F.Paste")
			(net "GND")
		)
	)
)
